FILE_TYPE = CONNECTIVITY;
{Allegro Design Entry HDL 16.6-p007 (v16-6-112F) 10/10/2012}
"PAGE_NUMBER" = 67;
0"NC";
1"UPI_CPU1_CPU0_P0P0_DN<19..0>";
2"UPI_CPU1_CPU0_P0P0_DP<19..0>";
3"UPI_CPU0_CPU1_P0P0_DN<19..0>";
4"UPI_CPU0_CPU1_P0P0_DP<19..0>";
5"UPI_CPU0_CPU1_P0P0_DP<0>";
6"UPI_CPU0_CPU1_P0P0_DN<1>";
7"UPI_CPU0_CPU1_P0P0_DN<2>";
8"UPI_CPU0_CPU1_P0P0_DP<3>";
9"UPI_CPU0_CPU1_P0P0_DP<4>";
10"UPI_CPU0_CPU1_P0P0_DP<5>";
11"UPI_CPU0_CPU1_P0P0_DP<6>";
12"UPI_CPU0_CPU1_P0P0_DP<7>";
13"UPI_CPU0_CPU1_P0P0_DP<8>";
14"UPI_CPU0_CPU1_P0P0_DP<9>";
15"UPI_CPU0_CPU1_P0P0_DN<0>";
16"UPI_CPU0_CPU1_P0P0_DP<1>";
17"UPI_CPU0_CPU1_P0P0_DP<2>";
18"UPI_CPU0_CPU1_P0P0_DN<3>";
19"UPI_CPU0_CPU1_P0P0_DN<4>";
20"UPI_CPU0_CPU1_P0P0_DN<5>";
21"UPI_CPU0_CPU1_P0P0_DN<6>";
22"UPI_CPU0_CPU1_P0P0_DN<7>";
23"UPI_CPU0_CPU1_P0P0_DN<8>";
24"UPI_CPU0_CPU1_P0P0_DN<9>";
25"UPI_CPU0_CPU1_P0P0_DP<10>";
26"UPI_CPU0_CPU1_P0P0_DN<11>";
27"UPI_CPU0_CPU1_P0P0_DP<12>";
28"UPI_CPU0_CPU1_P0P0_DP<13>";
29"UPI_CPU0_CPU1_P0P0_DN<14>";
30"UPI_CPU0_CPU1_P0P0_DP<15>";
31"UPI_CPU0_CPU1_P0P0_DP<16>";
32"UPI_CPU0_CPU1_P0P0_DP<17>";
33"UPI_CPU0_CPU1_P0P0_DN<18>";
34"UPI_CPU0_CPU1_P0P0_DN<19>";
35"UPI_CPU0_CPU1_P0P0_DN<10>";
36"UPI_CPU0_CPU1_P0P0_DP<11>";
37"UPI_CPU0_CPU1_P0P0_DN<12>";
38"UPI_CPU0_CPU1_P0P0_DN<13>";
39"UPI_CPU0_CPU1_P0P0_DP<14>";
40"UPI_CPU0_CPU1_P0P0_DN<15>";
41"UPI_CPU0_CPU1_P0P0_DN<16>";
42"UPI_CPU0_CPU1_P0P0_DN<17>";
43"UPI_CPU0_CPU1_P0P0_DP<18>";
44"UPI_CPU0_CPU1_P0P0_DP<19>";
45"UPI_CPU1_CPU0_P0P0_DP<0>";
46"UPI_CPU1_CPU0_P0P0_DP<1>";
47"UPI_CPU1_CPU0_P0P0_DN<2>";
48"UPI_CPU1_CPU0_P0P0_DN<3>";
49"UPI_CPU1_CPU0_P0P0_DN<4>";
50"UPI_CPU1_CPU0_P0P0_DP<5>";
51"UPI_CPU1_CPU0_P0P0_DN<6>";
52"UPI_CPU1_CPU0_P0P0_DN<7>";
53"UPI_CPU1_CPU0_P0P0_DP<8>";
54"UPI_CPU1_CPU0_P0P0_DN<9>";
55"UPI_CPU1_CPU0_P0P0_DN<0>";
56"UPI_CPU1_CPU0_P0P0_DN<1>";
57"UPI_CPU1_CPU0_P0P0_DP<2>";
58"UPI_CPU1_CPU0_P0P0_DP<3>";
59"UPI_CPU1_CPU0_P0P0_DP<4>";
60"UPI_CPU1_CPU0_P0P0_DN<5>";
61"UPI_CPU1_CPU0_P0P0_DP<6>";
62"UPI_CPU1_CPU0_P0P0_DP<7>";
63"UPI_CPU1_CPU0_P0P0_DN<8>";
64"UPI_CPU1_CPU0_P0P0_DP<9>";
65"UPI_CPU1_CPU0_P0P0_DN<10>";
66"UPI_CPU1_CPU0_P0P0_DN<11>";
67"UPI_CPU1_CPU0_P0P0_DN<12>";
68"UPI_CPU1_CPU0_P0P0_DN<13>";
69"UPI_CPU1_CPU0_P0P0_DN<14>";
70"UPI_CPU1_CPU0_P0P0_DN<15>";
71"UPI_CPU1_CPU0_P0P0_DN<16>";
72"UPI_CPU1_CPU0_P0P0_DP<17>";
73"UPI_CPU1_CPU0_P0P0_DP<18>";
74"UPI_CPU1_CPU0_P0P0_DN<19>";
75"UPI_CPU1_CPU0_P0P0_DP<10>";
76"UPI_CPU1_CPU0_P0P0_DP<11>";
77"UPI_CPU1_CPU0_P0P0_DP<12>";
78"UPI_CPU1_CPU0_P0P0_DP<13>";
79"UPI_CPU1_CPU0_P0P0_DP<14>";
80"UPI_CPU1_CPU0_P0P0_DP<15>";
81"UPI_CPU1_CPU0_P0P0_DP<16>";
82"UPI_CPU1_CPU0_P0P0_DN<17>";
83"UPI_CPU1_CPU0_P0P0_DN<18>";
84"UPI_CPU1_CPU0_P0P0_DP<19>";
%"TAP"
"1","(-5225,2125)","2","mstr_standard","I100";
;
HDL_TAP"TRUE"
BODY_TYPE"PLUMBING"
CDS_LIB"mstr_standard";
"B \NAC \NWC"4;
"S \NAC"
BN"11"36;
%"TAP"
"1","(-5225,2025)","2","mstr_standard","I101";
;
HDL_TAP"TRUE"
BODY_TYPE"PLUMBING"
CDS_LIB"mstr_standard";
"B \NAC \NWC"4;
"S \NAC"
BN"9"14;
%"TAP"
"1","(-5225,1975)","2","mstr_standard","I102";
;
HDL_TAP"TRUE"
BODY_TYPE"PLUMBING"
CDS_LIB"mstr_standard";
"B \NAC \NWC"4;
"S \NAC"
BN"8"13;
%"TAP"
"1","(-5225,1925)","2","mstr_standard","I103";
;
HDL_TAP"TRUE"
BODY_TYPE"PLUMBING"
CDS_LIB"mstr_standard";
"B \NAC \NWC"4;
"S \NAC"
BN"7"12;
%"TAP"
"1","(-5225,1875)","2","mstr_standard","I104";
;
HDL_TAP"TRUE"
BODY_TYPE"PLUMBING"
CDS_LIB"mstr_standard";
"B \NAC \NWC"4;
"S \NAC"
BN"6"11;
%"TAP"
"1","(-5225,1825)","2","mstr_standard","I105";
;
HDL_TAP"TRUE"
BODY_TYPE"PLUMBING"
CDS_LIB"mstr_standard";
"B \NAC \NWC"4;
"S \NAC"
BN"5"10;
%"TAP"
"1","(-5225,2675)","2","mstr_standard","I106";
;
HDL_TAP"TRUE"
BODY_TYPE"PLUMBING"
CDS_LIB"mstr_standard";
"B \NAC \NWC"4;
"S \NAC"
BN"1"16;
%"TAP"
"1","(-5225,1575)","2","mstr_standard","I107";
;
HDL_TAP"TRUE"
BODY_TYPE"PLUMBING"
CDS_LIB"mstr_standard";
"B \NAC \NWC"4;
"S \NAC"
BN"0"5;
%"TAP"
"1","(-5225,3275)","2","mstr_standard","I108";
;
HDL_TAP"TRUE"
BODY_TYPE"PLUMBING"
CDS_LIB"mstr_standard";
"B \NAC \NWC"4;
"S \NAC"
BN"13"28;
%"TAP"
"1","(-2575,3575)","0","mstr_standard","I109";
;
HDL_TAP"TRUE"
BODY_TYPE"PLUMBING"
CDS_LIB"mstr_standard";
"B \NAC \NWC"1;
"S \NAC"
BN"19"74;
%"TAP"
"1","(-2575,3425)","0","mstr_standard","I110";
;
HDL_TAP"TRUE"
BODY_TYPE"PLUMBING"
CDS_LIB"mstr_standard";
"B \NAC \NWC"1;
"S \NAC"
BN"16"71;
%"TAP"
"1","(-2575,3375)","0","mstr_standard","I111";
;
HDL_TAP"TRUE"
BODY_TYPE"PLUMBING"
CDS_LIB"mstr_standard";
"B \NAC \NWC"1;
"S \NAC"
BN"15"70;
%"TAP"
"1","(-2575,3275)","0","mstr_standard","I112";
;
HDL_TAP"TRUE"
BODY_TYPE"PLUMBING"
CDS_LIB"mstr_standard";
"B \NAC \NWC"1;
"S \NAC"
BN"13"68;
%"TAP"
"1","(-2575,3225)","0","mstr_standard","I113";
;
HDL_TAP"TRUE"
BODY_TYPE"PLUMBING"
CDS_LIB"mstr_standard";
"B \NAC \NWC"1;
"S \NAC"
BN"12"67;
%"TAP"
"1","(-2575,3175)","0","mstr_standard","I114";
;
HDL_TAP"TRUE"
BODY_TYPE"PLUMBING"
CDS_LIB"mstr_standard";
"B \NAC \NWC"1;
"S \NAC"
BN"11"66;
%"TAP"
"1","(-2575,3025)","0","mstr_standard","I115";
;
HDL_TAP"TRUE"
BODY_TYPE"PLUMBING"
CDS_LIB"mstr_standard";
"B \NAC \NWC"1;
"S \NAC"
BN"8"63;
%"TAP"
"1","(-2575,1875)","0","mstr_standard","I116";
;
HDL_TAP"TRUE"
BODY_TYPE"PLUMBING"
CDS_LIB"mstr_standard";
"B \NAC \NWC"1;
"S \NAC"
BN"6"51;
%"TAP"
"1","(-2575,1775)","0","mstr_standard","I117";
;
HDL_TAP"TRUE"
BODY_TYPE"PLUMBING"
CDS_LIB"mstr_standard";
"B \NAC \NWC"1;
"S \NAC"
BN"4"49;
%"TAP"
"1","(-2575,2675)","0","mstr_standard","I118";
;
HDL_TAP"TRUE"
BODY_TYPE"PLUMBING"
CDS_LIB"mstr_standard";
"B \NAC \NWC"1;
"S \NAC"
BN"1"56;
%"TAP"
"1","(-2575,2625)","0","mstr_standard","I119";
;
HDL_TAP"TRUE"
BODY_TYPE"PLUMBING"
CDS_LIB"mstr_standard";
"B \NAC \NWC"1;
"S \NAC"
BN"0"55;
%"TAP"
"1","(-2900,2525)","0","mstr_standard","I120";
;
HDL_TAP"TRUE"
BODY_TYPE"PLUMBING"
CDS_LIB"mstr_standard";
"B \NAC \NWC"2;
"S \NAC"
BN"19"84;
%"TAP"
"1","(-2900,2375)","0","mstr_standard","I121";
;
HDL_TAP"TRUE"
BODY_TYPE"PLUMBING"
CDS_LIB"mstr_standard";
"B \NAC \NWC"2;
"S \NAC"
BN"16"81;
%"TAP"
"1","(-2900,2325)","0","mstr_standard","I122";
;
HDL_TAP"TRUE"
BODY_TYPE"PLUMBING"
CDS_LIB"mstr_standard";
"B \NAC \NWC"2;
"S \NAC"
BN"15"80;
%"TAP"
"1","(-2900,2225)","0","mstr_standard","I123";
;
HDL_TAP"TRUE"
BODY_TYPE"PLUMBING"
CDS_LIB"mstr_standard";
"B \NAC \NWC"2;
"S \NAC"
BN"13"78;
%"TAP"
"1","(-2900,2175)","0","mstr_standard","I124";
;
HDL_TAP"TRUE"
BODY_TYPE"PLUMBING"
CDS_LIB"mstr_standard";
"B \NAC \NWC"2;
"S \NAC"
BN"12"77;
%"TAP"
"1","(-2900,2125)","0","mstr_standard","I125";
;
HDL_TAP"TRUE"
BODY_TYPE"PLUMBING"
CDS_LIB"mstr_standard";
"B \NAC \NWC"2;
"S \NAC"
BN"11"76;
%"TAP"
"1","(-2900,1975)","0","mstr_standard","I126";
;
HDL_TAP"TRUE"
BODY_TYPE"PLUMBING"
CDS_LIB"mstr_standard";
"B \NAC \NWC"2;
"S \NAC"
BN"8"53;
%"TAP"
"1","(-2900,2925)","0","mstr_standard","I127";
;
HDL_TAP"TRUE"
BODY_TYPE"PLUMBING"
CDS_LIB"mstr_standard";
"B \NAC \NWC"2;
"S \NAC"
BN"6"61;
%"TAP"
"1","(-2900,2825)","0","mstr_standard","I128";
;
HDL_TAP"TRUE"
BODY_TYPE"PLUMBING"
CDS_LIB"mstr_standard";
"B \NAC \NWC"2;
"S \NAC"
BN"4"59;
%"TAP"
"1","(-2900,1625)","0","mstr_standard","I129";
;
HDL_TAP"TRUE"
BODY_TYPE"PLUMBING"
CDS_LIB"mstr_standard";
"B \NAC \NWC"2;
"S \NAC"
BN"1"46;
%"TAP"
"1","(-2900,1575)","0","mstr_standard","I130";
;
HDL_TAP"TRUE"
BODY_TYPE"PLUMBING"
CDS_LIB"mstr_standard";
"B \NAC \NWC"2;
"S \NAC"
BN"0"45;
%"TAP"
"1","(-5500,1625)","2","mstr_standard","I131";
;
HDL_TAP"TRUE"
BODY_TYPE"PLUMBING"
CDS_LIB"mstr_standard";
"B \NAC \NWC"3;
"S \NAC"
BN"1"6;
%"SKX_EXT_B"
"13","(-4050,2575)","0","chpset_lib","I132";
;
CDS_SEC"13"
CDS_LOCATION"U2D1"
SEC"13"
CDS_LIB"chpset_lib"
SEC_TYPE"BGA1"
PACK_TYPE"BGA1"
MATERIAL"IC"
PART_NUMBER"TBD"
LOCATION"U2D1";
"UPI0_TX_DP<0>"
$PN"M1"55;
"UPI0_TX_DP<1>"
$PN"T1"56;
"UPI0_TX_DP<2>"
$PN"Y3"57;
"UPI0_TX_DP<3>"
$PN"W2"58;
"UPI0_TX_DP<4>"
$PN"AA2"59;
"UPI0_TX_DP<5>"
$PN"AD1"60;
"UPI0_TX_DP<6>"
$PN"AF3"61;
"UPI0_TX_DP<7>"
$PN"AG2"62;
"UPI0_TX_DP<8>"
$PN"AJ2"63;
"UPI0_TX_DP<9>"
$PN"AK1"64;
"UPI0_TX_DP<10>"
$PN"AK3"65;
"UPI0_TX_DP<11>"
$PN"AP3"66;
"UPI0_TX_DP<12>"
$PN"AP1"67;
"UPI0_TX_DP<13>"
$PN"AR2"68;
"UPI0_TX_DP<14>"
$PN"AR4"69;
"UPI0_TX_DP<15>"
$PN"AW4"70;
"UPI0_TX_DP<16>"
$PN"AY3"71;
"UPI0_TX_DP<17>"
$PN"BC2"72;
"UPI0_TX_DP<18>"
$PN"BD3"73;
"UPI0_TX_DP<19>"
$PN"BH3"74;
"UPI0_TX_DN<0>"
$PN"N2"45;
"UPI0_TX_DN<1>"
$PN"P1"46;
"UPI0_TX_DN<2>"
$PN"V3"47;
"UPI0_TX_DN<3>"
$PN"Y1"48;
"UPI0_TX_DN<4>"
$PN"AB3"49;
"UPI0_TX_DN<5>"
$PN"AC2"50;
"UPI0_TX_DN<6>"
$PN"AG4"51;
"UPI0_TX_DN<7>"
$PN"AE2"52;
"UPI0_TX_DN<8>"
$PN"AH3"53;
"UPI0_TX_DN<9>"
$PN"AL2"54;
"UPI0_TX_DN<10>"
$PN"AM3"75;
"UPI0_TX_DN<11>"
$PN"AN4"76;
"UPI0_TX_DN<12>"
$PN"AT1"77;
"UPI0_TX_DN<13>"
$PN"AT3"78;
"UPI0_TX_DN<14>"
$PN"AU4"79;
"UPI0_TX_DN<15>"
$PN"AV5"80;
"UPI0_TX_DN<16>"
$PN"BA4"81;
"UPI0_TX_DN<17>"
$PN"BB3"82;
"UPI0_TX_DN<18>"
$PN"BF3"83;
"UPI0_TX_DN<19>"
$PN"BG4"84;
"UPI0_RX_DP<0>"
$PN"AB9"15;
"UPI0_RX_DP<1>"
$PN"AC8"16;
"UPI0_RX_DP<2>"
$PN"AA6"17;
"UPI0_RX_DP<3>"
$PN"AC6"18;
"UPI0_RX_DP<4>"
$PN"AG6"19;
"UPI0_RX_DP<5>"
$PN"AF7"20;
"UPI0_RX_DP<6>"
$PN"AH7"21;
"UPI0_RX_DP<7>"
$PN"AK5"22;
"UPI0_RX_DP<8>"
$PN"AM7"23;
"UPI0_RX_DP<9>"
$PN"AL8"24;
"UPI0_RX_DP<10>"
$PN"AN8"25;
"UPI0_RX_DP<11>"
$PN"AU8"26;
"UPI0_RX_DP<12>"
$PN"AT9"27;
"UPI0_RX_DP<13>"
$PN"AY7"28;
"UPI0_RX_DP<14>"
$PN"BB7"29;
"UPI0_RX_DP<15>"
$PN"BF7"30;
"UPI0_RX_DP<16>"
$PN"AV9"31;
"UPI0_RX_DP<17>"
$PN"BB9"32;
"UPI0_RX_DP<18>"
$PN"BC10"33;
"UPI0_RX_DP<19>"
$PN"BA10"34;
"UPI0_RX_DN<0>"
$PN"AC10"5;
"UPI0_RX_DN<1>"
$PN"AA8"6;
"UPI0_RX_DN<2>"
$PN"AB7"7;
"UPI0_RX_DN<3>"
$PN"AD5"8;
"UPI0_RX_DN<4>"
$PN"AE6"9;
"UPI0_RX_DN<5>"
$PN"AG8"10;
"UPI0_RX_DN<6>"
$PN"AJ6"11;
"UPI0_RX_DN<7>"
$PN"AL6"12;
"UPI0_RX_DN<8>"
$PN"AK7"13;
"UPI0_RX_DN<9>"
$PN"AM9"14;
"UPI0_RX_DN<10>"
$PN"AP7"35;
"UPI0_RX_DN<11>"
$PN"AR8"36;
"UPI0_RX_DN<12>"
$PN"AU10"37;
"UPI0_RX_DN<13>"
$PN"BA8"38;
"UPI0_RX_DN<14>"
$PN"BC6"39;
"UPI0_RX_DN<15>"
$PN"BD7"40;
"UPI0_RX_DN<16>"
$PN"AW8"41;
"UPI0_RX_DN<17>"
$PN"AY9"42;
"UPI0_RX_DN<18>"
$PN"BD9"43;
"UPI0_RX_DN<19>"
$PN"BB11"44;
%"TAP"
"1","(-5500,2075)","2","mstr_standard","I14";
;
HDL_TAP"TRUE"
BODY_TYPE"PLUMBING"
CDS_LIB"mstr_standard";
"B \NAC \NWC"3;
"S \NAC"
BN"10"35;
%"TAP"
"1","(-5500,2175)","2","mstr_standard","I16";
;
HDL_TAP"TRUE"
BODY_TYPE"PLUMBING"
CDS_LIB"mstr_standard";
"B \NAC \NWC"3;
"S \NAC"
BN"12"37;
%"TAP"
"1","(-5500,2375)","2","mstr_standard","I20";
;
HDL_TAP"TRUE"
BODY_TYPE"PLUMBING"
CDS_LIB"mstr_standard";
"B \NAC \NWC"3;
"S \NAC"
BN"16"41;
%"TAP"
"1","(-5500,2425)","2","mstr_standard","I21";
;
HDL_TAP"TRUE"
BODY_TYPE"PLUMBING"
CDS_LIB"mstr_standard";
"B \NAC \NWC"3;
"S \NAC"
BN"17"42;
%"TAP"
"1","(-5225,2725)","2","mstr_standard","I26";
;
HDL_TAP"TRUE"
BODY_TYPE"PLUMBING"
CDS_LIB"mstr_standard";
"B \NAC \NWC"4;
"S \NAC"
BN"2"17;
%"TAP"
"1","(-5225,1725)","2","mstr_standard","I27";
;
HDL_TAP"TRUE"
BODY_TYPE"PLUMBING"
CDS_LIB"mstr_standard";
"B \NAC \NWC"4;
"S \NAC"
BN"3"8;
%"TAP"
"1","(-5225,1775)","2","mstr_standard","I28";
;
HDL_TAP"TRUE"
BODY_TYPE"PLUMBING"
CDS_LIB"mstr_standard";
"B \NAC \NWC"4;
"S \NAC"
BN"4"9;
%"TAP"
"1","(-5225,3125)","2","mstr_standard","I34";
;
HDL_TAP"TRUE"
BODY_TYPE"PLUMBING"
CDS_LIB"mstr_standard";
"B \NAC \NWC"4;
"S \NAC"
BN"10"25;
%"TAP"
"1","(-5225,3225)","2","mstr_standard","I36";
;
HDL_TAP"TRUE"
BODY_TYPE"PLUMBING"
CDS_LIB"mstr_standard";
"B \NAC \NWC"4;
"S \NAC"
BN"12"27;
%"TAP"
"1","(-5225,3425)","2","mstr_standard","I40";
;
HDL_TAP"TRUE"
BODY_TYPE"PLUMBING"
CDS_LIB"mstr_standard";
"B \NAC \NWC"4;
"S \NAC"
BN"16"31;
%"TAP"
"1","(-5225,3475)","2","mstr_standard","I41";
;
HDL_TAP"TRUE"
BODY_TYPE"PLUMBING"
CDS_LIB"mstr_standard";
"B \NAC \NWC"4;
"S \NAC"
BN"17"32;
%"TAP"
"1","(-5225,2475)","2","mstr_standard","I42";
;
HDL_TAP"TRUE"
BODY_TYPE"PLUMBING"
CDS_LIB"mstr_standard";
"B \NAC \NWC"4;
"S \NAC"
BN"18"43;
%"TAP"
"1","(-5225,2525)","2","mstr_standard","I43";
;
HDL_TAP"TRUE"
BODY_TYPE"PLUMBING"
CDS_LIB"mstr_standard";
"B \NAC \NWC"4;
"S \NAC"
BN"19"44;
%"TAP"
"1","(-2575,1675)","0","mstr_standard","I46";
;
HDL_TAP"TRUE"
BODY_TYPE"PLUMBING"
CDS_LIB"mstr_standard";
"B \NAC \NWC"1;
"S \NAC"
BN"2"47;
%"TAP"
"1","(-2575,1725)","0","mstr_standard","I48";
;
HDL_TAP"TRUE"
BODY_TYPE"PLUMBING"
CDS_LIB"mstr_standard";
"B \NAC \NWC"1;
"S \NAC"
BN"3"48;
%"TAP"
"1","(-2575,2875)","0","mstr_standard","I49";
;
HDL_TAP"TRUE"
BODY_TYPE"PLUMBING"
CDS_LIB"mstr_standard";
"B \NAC \NWC"1;
"S \NAC"
BN"5"60;
%"TAP"
"1","(-5500,1675)","2","mstr_standard","I5";
;
HDL_TAP"TRUE"
BODY_TYPE"PLUMBING"
CDS_LIB"mstr_standard";
"B \NAC \NWC"3;
"S \NAC"
BN"2"7;
%"TAP"
"1","(-2575,1925)","0","mstr_standard","I51";
;
HDL_TAP"TRUE"
BODY_TYPE"PLUMBING"
CDS_LIB"mstr_standard";
"B \NAC \NWC"1;
"S \NAC"
BN"7"52;
%"TAP"
"1","(-2575,3125)","0","mstr_standard","I53";
;
HDL_TAP"TRUE"
BODY_TYPE"PLUMBING"
CDS_LIB"mstr_standard";
"B \NAC \NWC"1;
"S \NAC"
BN"10"65;
%"TAP"
"1","(-2575,2025)","0","mstr_standard","I54";
;
HDL_TAP"TRUE"
BODY_TYPE"PLUMBING"
CDS_LIB"mstr_standard";
"B \NAC \NWC"1;
"S \NAC"
BN"9"54;
%"TAP"
"1","(-2575,3325)","0","mstr_standard","I58";
;
HDL_TAP"TRUE"
BODY_TYPE"PLUMBING"
CDS_LIB"mstr_standard";
"B \NAC \NWC"1;
"S \NAC"
BN"14"69;
%"TAP"
"1","(-5500,2825)","2","mstr_standard","I6";
;
HDL_TAP"TRUE"
BODY_TYPE"PLUMBING"
CDS_LIB"mstr_standard";
"B \NAC \NWC"3;
"S \NAC"
BN"4"19;
%"TAP"
"1","(-2575,2425)","0","mstr_standard","I61";
;
HDL_TAP"TRUE"
BODY_TYPE"PLUMBING"
CDS_LIB"mstr_standard";
"B \NAC \NWC"1;
"S \NAC"
BN"17"82;
%"TAP"
"1","(-2575,2475)","0","mstr_standard","I62";
;
HDL_TAP"TRUE"
BODY_TYPE"PLUMBING"
CDS_LIB"mstr_standard";
"B \NAC \NWC"1;
"S \NAC"
BN"18"83;
%"TAP"
"1","(-2900,2725)","0","mstr_standard","I66";
;
HDL_TAP"TRUE"
BODY_TYPE"PLUMBING"
CDS_LIB"mstr_standard";
"B \NAC \NWC"2;
"S \NAC"
BN"2"57;
%"TAP"
"1","(-2900,2775)","0","mstr_standard","I67";
;
HDL_TAP"TRUE"
BODY_TYPE"PLUMBING"
CDS_LIB"mstr_standard";
"B \NAC \NWC"2;
"S \NAC"
BN"3"58;
%"TAP"
"1","(-2900,1825)","0","mstr_standard","I69";
;
HDL_TAP"TRUE"
BODY_TYPE"PLUMBING"
CDS_LIB"mstr_standard";
"B \NAC \NWC"2;
"S \NAC"
BN"5"50;
%"TAP"
"1","(-5500,2775)","2","mstr_standard","I7";
;
HDL_TAP"TRUE"
BODY_TYPE"PLUMBING"
CDS_LIB"mstr_standard";
"B \NAC \NWC"3;
"S \NAC"
BN"3"18;
%"TAP"
"1","(-2900,2975)","0","mstr_standard","I72";
;
HDL_TAP"TRUE"
BODY_TYPE"PLUMBING"
CDS_LIB"mstr_standard";
"B \NAC \NWC"2;
"S \NAC"
BN"7"62;
%"TAP"
"1","(-2900,3075)","0","mstr_standard","I73";
;
HDL_TAP"TRUE"
BODY_TYPE"PLUMBING"
CDS_LIB"mstr_standard";
"B \NAC \NWC"2;
"S \NAC"
BN"9"64;
%"TAP"
"1","(-2900,2075)","0","mstr_standard","I74";
;
HDL_TAP"TRUE"
BODY_TYPE"PLUMBING"
CDS_LIB"mstr_standard";
"B \NAC \NWC"2;
"S \NAC"
BN"10"75;
%"TAP"
"1","(-2900,2275)","0","mstr_standard","I78";
;
HDL_TAP"TRUE"
BODY_TYPE"PLUMBING"
CDS_LIB"mstr_standard";
"B \NAC \NWC"2;
"S \NAC"
BN"14"79;
%"TAP"
"1","(-2900,3475)","0","mstr_standard","I81";
;
HDL_TAP"TRUE"
BODY_TYPE"PLUMBING"
CDS_LIB"mstr_standard";
"B \NAC \NWC"2;
"S \NAC"
BN"17"72;
%"TAP"
"1","(-2900,3525)","0","mstr_standard","I83";
;
HDL_TAP"TRUE"
BODY_TYPE"PLUMBING"
CDS_LIB"mstr_standard";
"B \NAC \NWC"2;
"S \NAC"
BN"18"73;
%"TAP"
"1","(-5500,3525)","2","mstr_standard","I86";
;
HDL_TAP"TRUE"
BODY_TYPE"PLUMBING"
CDS_LIB"mstr_standard";
"B \NAC \NWC"3;
"S \NAC"
BN"18"33;
%"TAP"
"1","(-5500,3575)","2","mstr_standard","I87";
;
HDL_TAP"TRUE"
BODY_TYPE"PLUMBING"
CDS_LIB"mstr_standard";
"B \NAC \NWC"3;
"S \NAC"
BN"19"34;
%"TAP"
"1","(-5500,2625)","2","mstr_standard","I88";
;
HDL_TAP"TRUE"
BODY_TYPE"PLUMBING"
CDS_LIB"mstr_standard";
"B \NAC \NWC"3;
"S \NAC"
BN"0"15;
%"TAP"
"1","(-5500,2875)","2","mstr_standard","I89";
;
HDL_TAP"TRUE"
BODY_TYPE"PLUMBING"
CDS_LIB"mstr_standard";
"B \NAC \NWC"3;
"S \NAC"
BN"5"20;
%"TAP"
"1","(-5500,2925)","2","mstr_standard","I90";
;
HDL_TAP"TRUE"
BODY_TYPE"PLUMBING"
CDS_LIB"mstr_standard";
"B \NAC \NWC"3;
"S \NAC"
BN"6"21;
%"TAP"
"1","(-5500,2975)","2","mstr_standard","I91";
;
HDL_TAP"TRUE"
BODY_TYPE"PLUMBING"
CDS_LIB"mstr_standard";
"B \NAC \NWC"3;
"S \NAC"
BN"7"22;
%"TAP"
"1","(-5500,3025)","2","mstr_standard","I92";
;
HDL_TAP"TRUE"
BODY_TYPE"PLUMBING"
CDS_LIB"mstr_standard";
"B \NAC \NWC"3;
"S \NAC"
BN"8"23;
%"TAP"
"1","(-5500,3075)","2","mstr_standard","I93";
;
HDL_TAP"TRUE"
BODY_TYPE"PLUMBING"
CDS_LIB"mstr_standard";
"B \NAC \NWC"3;
"S \NAC"
BN"9"24;
%"TAP"
"1","(-5500,2225)","2","mstr_standard","I94";
;
HDL_TAP"TRUE"
BODY_TYPE"PLUMBING"
CDS_LIB"mstr_standard";
"B \NAC \NWC"3;
"S \NAC"
BN"13"38;
%"TAP"
"1","(-5500,3325)","2","mstr_standard","I95";
;
HDL_TAP"TRUE"
BODY_TYPE"PLUMBING"
CDS_LIB"mstr_standard";
"B \NAC \NWC"3;
"S \NAC"
BN"14"29;
%"TAP"
"1","(-5500,2325)","2","mstr_standard","I96";
;
HDL_TAP"TRUE"
BODY_TYPE"PLUMBING"
CDS_LIB"mstr_standard";
"B \NAC \NWC"3;
"S \NAC"
BN"15"40;
%"TAP"
"1","(-5500,3175)","2","mstr_standard","I97";
;
HDL_TAP"TRUE"
BODY_TYPE"PLUMBING"
CDS_LIB"mstr_standard";
"B \NAC \NWC"3;
"S \NAC"
BN"11"26;
%"TAP"
"1","(-5225,3375)","2","mstr_standard","I98";
;
HDL_TAP"TRUE"
BODY_TYPE"PLUMBING"
CDS_LIB"mstr_standard";
"B \NAC \NWC"4;
"S \NAC"
BN"15"30;
%"TAP"
"1","(-5225,2275)","2","mstr_standard","I99";
;
HDL_TAP"TRUE"
BODY_TYPE"PLUMBING"
CDS_LIB"mstr_standard";
"B \NAC \NWC"4;
"S \NAC"
BN"14"39;
END.
